(kicad_pcb
	(version 20260206)
	(generator "pcbnew")
	(generator_version "10.0")
	(general
		(thickness 1.6)
		(legacy_teardrops no)
	)
	(paper "A4")
	(title_block
		(title "peb — Lightning_PEB_BRD.brd")
		(comment 1 "Lightning (Wiwynn / Facebook NVMe JBOF) / footprints 1337-1343 of 2563")
	)
	(layers
		(0 "F.Cu" signal "TOP")
		(4 "In1.Cu" signal "L2GND")
		(6 "In2.Cu" signal "L3")
		(8 "In3.Cu" signal "L4VCC")
		(10 "In4.Cu" signal "L5VCC")
		(12 "In5.Cu" signal "L6")
		(14 "In6.Cu" signal "L7GND")
		(2 "B.Cu" signal "BOTTOM")
		(9 "F.Adhes" user "F.Adhesive")
		(11 "B.Adhes" user "B.Adhesive")
		(13 "F.Paste" user "Package Geometry/Pastemask Top")
		(15 "B.Paste" user "Package Geometry/Pastemask Bottom")
		(5 "F.SilkS" user "Ref Des/Silkscreen Top")
		(7 "B.SilkS" user "Ref Des/Silkscreen Bottom")
		(1 "F.Mask" user "Board Geometry/Soldermask Top")
		(3 "B.Mask" user "Board Geometry/Soldermask Bottom")
		(17 "Dwgs.User" user "User.Drawings")
		(19 "Cmts.User" user "User.Comments")
		(21 "Eco1.User" user "User.Eco1")
		(23 "Eco2.User" user "User.Eco2")
		(25 "Edge.Cuts" user "Board Geometry/Outline")
		(27 "Margin" user)
		(31 "F.CrtYd" user "Package Geometry/Place Bound Top")
		(29 "B.CrtYd" user "Package Geometry/Place Bound Bottom")
		(35 "F.Fab" user "Ref Des/Assembly Top")
		(33 "B.Fab" user "Ref Des/Assembly Bottom")
	)
	(footprint ""
		(layer "F.Cu")
		(at 73.4822 -118.11 -90)
		(property "Reference" "C282"
			(at 0 0 270)
			(layer "F.SilkS")
			(hide yes)
			(effects
				(font
					(size 1.27 1.27)
				)
			)
		)
		(property "Value" "SCD1U16V2KX-3GP"
			(at 1.1811 -2.7051 270)
			(unlocked yes)
			(layer "F.Fab")
			(hide yes)
			(effects
				(font
					(size 1.016 1.016)
					(thickness 0.1524)
				)
			)
		)
		(property "Device Type" "C402H22"
			(at 1.1811 -4.2291 270)
			(unlocked yes)
			(layer "F.Fab")
			(hide yes)
			(effects
				(font
					(size 1.016 1.016)
					(thickness 0.1524)
				)
			)
		)
		(duplicate_pad_numbers_are_jumpers no)
		(fp_rect
			(start -0.4318 0.9525)
			(end 0.4318 -0.9525)
			(stroke
				(width 0)
				(type default)
			)
			(fill no)
			(layer "F.CrtYd")
		)
		(fp_rect
			(start -0.4318 0.9525)
			(end 0.4318 -0.9525)
			(stroke
				(width 0)
				(type default)
			)
			(fill no)
			(layer "F.Fab")
		)
		(pad "1" smd custom
			(at 0 -0.4445 270)
			(size 0.1524 0.1524)
			(layers "F.Cu" "F.Mask" "F.Paste")
			(net "P3V3_STBY")
			(options
				(clearance outline)
				(anchor circle)
			)
			(primitives
				(gr_poly
					(pts
						(arc
							(start 0.3048 -0.2032)
							(mid 0.275042 -0.275042)
							(end 0.2032 -0.3048)
						)
						(arc
							(start -0.2032 -0.3048)
							(mid -0.275042 -0.275042)
							(end -0.3048 -0.2032)
						)
						(arc
							(start -0.3048 0.2032)
							(mid -0.275042 0.275042)
							(end -0.2032 0.3048)
						)
						(arc
							(start 0.2032 0.3048)
							(mid 0.275042 0.275042)
							(end 0.3048 0.2032)
						)
					)
					(width 0)
					(fill yes)
				)
			)
		)
		(pad "2" smd custom
			(at 0 0.4445 270)
			(size 0.1524 0.1524)
			(layers "F.Cu" "F.Mask" "F.Paste")
			(net "GND")
			(options
				(clearance outline)
				(anchor circle)
			)
			(primitives
				(gr_poly
					(pts
						(arc
							(start 0.3048 -0.2032)
							(mid 0.275042 -0.275042)
							(end 0.2032 -0.3048)
						)
						(arc
							(start -0.2032 -0.3048)
							(mid -0.275042 -0.275042)
							(end -0.3048 -0.2032)
						)
						(arc
							(start -0.3048 0.2032)
							(mid -0.275042 0.275042)
							(end -0.2032 0.3048)
						)
						(arc
							(start 0.2032 0.3048)
							(mid 0.275042 0.275042)
							(end 0.3048 0.2032)
						)
					)
					(width 0)
					(fill yes)
				)
			)
		)
	)
	(footprint ""
		(layer "F.Cu")
		(at 226.314 -78.1304 180)
		(property "Reference" "R587"
			(at 0 0 180)
			(layer "F.SilkS")
			(hide yes)
			(effects
				(font
					(size 1.27 1.27)
				)
			)
		)
		(property "Value" "0R2J-2-GP"
			(at 0.064008 -3.993896 180)
			(unlocked yes)
			(layer "F.Fab")
			(hide yes)
			(effects
				(font
					(size 1.016 1.016)
					(thickness 0.1524)
				)
			)
		)
		(property "Device Type" "R402H16"
			(at 0.064008 -5.517896 180)
			(unlocked yes)
			(layer "F.Fab")
			(hide yes)
			(effects
				(font
					(size 1.016 1.016)
					(thickness 0.1524)
				)
			)
		)
		(duplicate_pad_numbers_are_jumpers no)
		(fp_line
			(start 0.508 -0.9398)
			(end -0.508 -0.9398)
			(stroke
				(width 0.1524)
				(type default)
			)
			(layer "F.SilkS")
		)
		(fp_line
			(start -0.508 -0.9398)
			(end -0.508 0.9398)
			(stroke
				(width 0.1524)
				(type default)
			)
			(layer "F.SilkS")
		)
		(fp_rect
			(start -0.508 0.9398)
			(end 0.508 -0.9398)
			(stroke
				(width 0)
				(type default)
			)
			(fill no)
			(layer "F.CrtYd")
		)
		(fp_rect
			(start -0.508 0.9398)
			(end 0.508 -0.9398)
			(stroke
				(width 0)
				(type default)
			)
			(fill no)
			(layer "F.Fab")
		)
		(pad "1" smd custom
			(at 0 -0.4445 180)
			(size 0.1397 0.1397)
			(layers "F.Cu" "F.Mask" "F.Paste")
			(net "BMC_I2C5_D_PEB_SDA")
			(options
				(clearance outline)
				(anchor circle)
			)
			(primitives
				(gr_poly
					(pts
						(arc
							(start -0.1778 -0.2794)
							(mid -0.249642 -0.249642)
							(end -0.2794 -0.1778)
						)
						(arc
							(start -0.2794 0.1778)
							(mid -0.249642 0.249642)
							(end -0.1778 0.2794)
						)
						(arc
							(start 0.1778 0.2794)
							(mid 0.249642 0.249642)
							(end 0.2794 0.1778)
						)
						(arc
							(start 0.2794 -0.1778)
							(mid 0.249642 -0.249642)
							(end 0.1778 -0.2794)
						)
					)
					(width 0)
					(fill yes)
				)
			)
		)
		(pad "2" smd custom
			(at 0 0.4445 180)
			(size 0.1397 0.1397)
			(layers "F.Cu" "F.Mask" "F.Paste")
			(net "TEMP_3_SDA")
			(options
				(clearance outline)
				(anchor circle)
			)
			(primitives
				(gr_poly
					(pts
						(arc
							(start -0.1778 -0.2794)
							(mid -0.249642 -0.249642)
							(end -0.2794 -0.1778)
						)
						(arc
							(start -0.2794 0.1778)
							(mid -0.249642 0.249642)
							(end -0.1778 0.2794)
						)
						(arc
							(start 0.1778 0.2794)
							(mid 0.249642 0.249642)
							(end 0.2794 0.1778)
						)
						(arc
							(start 0.2794 -0.1778)
							(mid 0.249642 -0.249642)
							(end 0.1778 -0.2794)
						)
					)
					(width 0)
					(fill yes)
				)
			)
		)
	)
	(footprint ""
		(layer "F.Cu")
		(at 70.993 -33.02 -90)
		(property "Reference" "PC31"
			(at 0 0 270)
			(layer "F.SilkS")
			(hide yes)
			(effects
				(font
					(size 1.27 1.27)
				)
			)
		)
		(property "Value" "SC1KP50V2KX-1GP"
			(at 1.1811 -2.7051 270)
			(unlocked yes)
			(layer "F.Fab")
			(hide yes)
			(effects
				(font
					(size 1.016 1.016)
					(thickness 0.1524)
				)
			)
		)
		(property "Device Type" "C402H22"
			(at 1.1811 -4.2291 270)
			(unlocked yes)
			(layer "F.Fab")
			(hide yes)
			(effects
				(font
					(size 1.016 1.016)
					(thickness 0.1524)
				)
			)
		)
		(duplicate_pad_numbers_are_jumpers no)
		(fp_rect
			(start -0.4318 0.9525)
			(end 0.4318 -0.9525)
			(stroke
				(width 0)
				(type default)
			)
			(fill no)
			(layer "F.CrtYd")
		)
		(fp_rect
			(start -0.4318 0.9525)
			(end 0.4318 -0.9525)
			(stroke
				(width 0)
				(type default)
			)
			(fill no)
			(layer "F.Fab")
		)
		(pad "1" smd custom
			(at 0 -0.4445 270)
			(size 0.1524 0.1524)
			(layers "F.Cu" "F.Mask" "F.Paste")
			(net "P3V3_STBY_LL_R")
			(options
				(clearance outline)
				(anchor circle)
			)
			(primitives
				(gr_poly
					(pts
						(arc
							(start 0.3048 -0.2032)
							(mid 0.275042 -0.275042)
							(end 0.2032 -0.3048)
						)
						(arc
							(start -0.2032 -0.3048)
							(mid -0.275042 -0.275042)
							(end -0.3048 -0.2032)
						)
						(arc
							(start -0.3048 0.2032)
							(mid -0.275042 0.275042)
							(end -0.2032 0.3048)
						)
						(arc
							(start 0.2032 0.3048)
							(mid 0.275042 0.275042)
							(end 0.3048 0.2032)
						)
					)
					(width 0)
					(fill yes)
				)
			)
		)
		(pad "2" smd custom
			(at 0 0.4445 270)
			(size 0.1524 0.1524)
			(layers "F.Cu" "F.Mask" "F.Paste")
			(net "P3V3_STBY_VFB")
			(options
				(clearance outline)
				(anchor circle)
			)
			(primitives
				(gr_poly
					(pts
						(arc
							(start 0.3048 -0.2032)
							(mid 0.275042 -0.275042)
							(end 0.2032 -0.3048)
						)
						(arc
							(start -0.2032 -0.3048)
							(mid -0.275042 -0.275042)
							(end -0.3048 -0.2032)
						)
						(arc
							(start -0.3048 0.2032)
							(mid -0.275042 0.275042)
							(end -0.2032 0.3048)
						)
						(arc
							(start 0.2032 0.3048)
							(mid 0.275042 0.275042)
							(end 0.3048 0.2032)
						)
					)
					(width 0)
					(fill yes)
				)
			)
		)
	)
	(footprint ""
		(layer "F.Cu")
		(at 147.7518 -89.535 180)
		(property "Reference" "PC90"
			(at 0 0 180)
			(layer "F.SilkS")
			(hide yes)
			(effects
				(font
					(size 1.27 1.27)
				)
			)
		)
		(property "Value" "SC22U6D3V5MX-5-GP"
			(at -0.0762 -6.1214 180)
			(unlocked yes)
			(layer "F.Fab")
			(hide yes)
			(effects
				(font
					(size 1.016 1.016)
					(thickness 0.1524)
				)
			)
		)
		(property "Device Type" "C805H56"
			(at -0.0762 -8.1534 180)
			(unlocked yes)
			(layer "F.Fab")
			(hide yes)
			(effects
				(font
					(size 1.016 1.016)
					(thickness 0.1524)
				)
			)
		)
		(duplicate_pad_numbers_are_jumpers no)
		(fp_line
			(start 0.635 0)
			(end -0.635 0)
			(stroke
				(width 0.508)
				(type default)
			)
			(layer "F.SilkS")
		)
		(fp_rect
			(start -0.9652 1.778)
			(end 0.9652 -1.778)
			(stroke
				(width 0)
				(type default)
			)
			(fill no)
			(layer "F.CrtYd")
		)
		(fp_poly
			(pts
				(xy -0.9652 -1.778) (xy 0.9652 -1.778) (xy 0.9652 1.778) (xy -0.9652 1.778)
			)
			(stroke
				(width 0)
				(type default)
			)
			(fill no)
			(layer "F.Fab")
		)
		(pad "1" smd rect
			(at 0 -0.9652 180)
			(size 1.397 1.143)
			(layers "F.Cu" "F.Mask" "F.Paste")
			(net "P1V8_PWR")
		)
		(pad "2" smd rect
			(at 0 0.9652 180)
			(size 1.397 1.143)
			(layers "F.Cu" "F.Mask" "F.Paste")
			(net "GND")
		)
	)
	(footprint ""
		(layer "F.Cu")
		(at 330.099924 -13.999972 -90)
		(property "Reference" "LED13"
			(at 0 0 270)
			(layer "F.SilkS")
			(hide yes)
			(effects
				(font
					(size 1.27 1.27)
				)
			)
		)
		(property "Value" "LED-YG-51-GP"
			(at -2.6924 -1.4224 270)
			(unlocked yes)
			(layer "F.Fab")
			(hide yes)
			(effects
				(font
					(size 1.016 1.016)
					(thickness 0.1524)
				)
			)
		)
		(property "Device Type" "LED1608AKH40"
			(at -2.6924 -2.9464 270)
			(unlocked yes)
			(layer "F.Fab")
			(hide yes)
			(effects
				(font
					(size 1.016 1.016)
					(thickness 0.1524)
				)
			)
		)
		(duplicate_pad_numbers_are_jumpers no)
		(fp_line
			(start -0.7493 1.651)
			(end -0.7493 1.1811)
			(stroke
				(width 0.3302)
				(type default)
			)
			(layer "F.SilkS")
		)
		(fp_line
			(start 0.7493 1.651)
			(end 0.7493 1.1811)
			(stroke
				(width 0.3302)
				(type default)
			)
			(layer "F.SilkS")
		)
		(fp_line
			(start -0.5969 1.5494)
			(end 0.5842 1.5494)
			(stroke
				(width 0.508)
				(type default)
			)
			(layer "F.SilkS")
		)
		(fp_line
			(start -0.6604 1.3716)
			(end -0.6604 -1.3716)
			(stroke
				(width 0.1524)
				(type default)
			)
			(layer "F.SilkS")
		)
		(fp_line
			(start 0.6604 1.3716)
			(end -0.6604 1.3716)
			(stroke
				(width 0.1524)
				(type default)
			)
			(layer "F.SilkS")
		)
		(fp_line
			(start -0.6604 -1.3716)
			(end 0.6604 -1.3716)
			(stroke
				(width 0.1524)
				(type default)
			)
			(layer "F.SilkS")
		)
		(fp_line
			(start 0.6604 -1.3716)
			(end 0.6604 1.3716)
			(stroke
				(width 0.1524)
				(type default)
			)
			(layer "F.SilkS")
		)
		(fp_rect
			(start -0.6223 1.3335)
			(end 0.6223 -1.3335)
			(stroke
				(width 0)
				(type default)
			)
			(fill no)
			(layer "F.CrtYd")
		)
		(fp_rect
			(start -0.6223 1.3335)
			(end 0.6223 -1.3335)
			(stroke
				(width 0)
				(type default)
			)
			(fill no)
			(layer "F.Fab")
		)
		(pad "A" smd custom
			(at 0 -0.762 270)
			(size 0.2159 0.2159)
			(layers "F.Cu" "F.Mask" "F.Paste")
			(net "LED_R_6")
			(options
				(clearance outline)
				(anchor circle)
			)
			(primitives
				(gr_poly
					(pts
						(arc
							(start -0.3302 -0.4318)
							(mid -0.402042 -0.402042)
							(end -0.4318 -0.3302)
						)
						(arc
							(start -0.4318 0.3302)
							(mid -0.402042 0.402042)
							(end -0.3302 0.4318)
						)
						(arc
							(start 0.3302 0.4318)
							(mid 0.402042 0.402042)
							(end 0.4318 0.3302)
						)
						(arc
							(start 0.4318 -0.3302)
							(mid 0.402042 -0.402042)
							(end 0.3302 -0.4318)
						)
					)
					(width 0)
					(fill yes)
				)
			)
		)
		(pad "K" smd custom
			(at 0 0.762 270)
			(size 0.2159 0.2159)
			(layers "F.Cu" "F.Mask" "F.Paste")
			(net "LED_Q_6")
			(options
				(clearance outline)
				(anchor circle)
			)
			(primitives
				(gr_poly
					(pts
						(arc
							(start -0.3302 -0.4318)
							(mid -0.402042 -0.402042)
							(end -0.4318 -0.3302)
						)
						(arc
							(start -0.4318 0.3302)
							(mid -0.402042 0.402042)
							(end -0.3302 0.4318)
						)
						(arc
							(start 0.3302 0.4318)
							(mid 0.402042 0.402042)
							(end 0.4318 0.3302)
						)
						(arc
							(start 0.4318 -0.3302)
							(mid 0.402042 -0.402042)
							(end 0.3302 -0.4318)
						)
					)
					(width 0)
					(fill yes)
				)
			)
		)
	)
	(footprint ""
		(layer "F.Cu")
		(at 31.9278 -193.3702 90)
		(property "Reference" "C7279"
			(at 0 0 90)
			(layer "F.SilkS")
			(hide yes)
			(effects
				(font
					(size 1.27 1.27)
				)
			)
		)
		(property "Value" "SCD033U50V3KX-1GP"
			(at 0 -2.8194 90)
			(unlocked yes)
			(layer "F.Fab")
			(hide yes)
			(effects
				(font
					(size 1.016 1.016)
					(thickness 0.1524)
				)
			)
		)
		(property "Device Type" "C603H36"
			(at 0 -4.3434 90)
			(unlocked yes)
			(layer "F.Fab")
			(hide yes)
			(effects
				(font
					(size 1.016 1.016)
					(thickness 0.1524)
				)
			)
		)
		(duplicate_pad_numbers_are_jumpers no)
		(fp_line
			(start 0.508 0)
			(end -0.508 0)
			(stroke
				(width 0.2032)
				(type default)
			)
			(layer "F.SilkS")
		)
		(fp_rect
			(start -0.5842 1.3335)
			(end 0.5842 -1.3335)
			(stroke
				(width 0)
				(type default)
			)
			(fill no)
			(layer "F.CrtYd")
		)
		(fp_rect
			(start -0.5842 1.3335)
			(end 0.5842 -1.3335)
			(stroke
				(width 0)
				(type default)
			)
			(fill no)
			(layer "F.Fab")
		)
		(pad "1" smd custom
			(at 0 -0.762 90)
			(size 0.2159 0.2159)
			(layers "F.Cu" "F.Mask" "F.Paste")
			(net "MB0_CM_GATE_R")
			(options
				(clearance outline)
				(anchor circle)
			)
			(primitives
				(gr_poly
					(pts
						(arc
							(start -0.3302 -0.4318)
							(mid -0.402042 -0.402042)
							(end -0.4318 -0.3302)
						)
						(arc
							(start -0.4318 0.3302)
							(mid -0.402042 0.402042)
							(end -0.3302 0.4318)
						)
						(arc
							(start 0.3302 0.4318)
							(mid 0.402042 0.402042)
							(end 0.4318 0.3302)
						)
						(arc
							(start 0.4318 -0.3302)
							(mid 0.402042 -0.402042)
							(end 0.3302 -0.4318)
						)
					)
					(width 0)
					(fill yes)
				)
			)
		)
		(pad "2" smd custom
			(at 0 0.762 90)
			(size 0.2159 0.2159)
			(layers "F.Cu" "F.Mask" "F.Paste")
			(net "GND")
			(options
				(clearance outline)
				(anchor circle)
			)
			(primitives
				(gr_poly
					(pts
						(arc
							(start -0.3302 -0.4318)
							(mid -0.402042 -0.402042)
							(end -0.4318 -0.3302)
						)
						(arc
							(start -0.4318 0.3302)
							(mid -0.402042 0.402042)
							(end -0.3302 0.4318)
						)
						(arc
							(start 0.3302 0.4318)
							(mid 0.402042 0.402042)
							(end 0.4318 0.3302)
						)
						(arc
							(start 0.4318 -0.3302)
							(mid 0.402042 -0.402042)
							(end 0.3302 -0.4318)
						)
					)
					(width 0)
					(fill yes)
				)
			)
		)
	)
	(footprint ""
		(layer "F.Cu")
		(at 22.479 -151.892 90)
		(property "Reference" "U80"
			(at 0 0 90)
			(layer "F.SilkS")
			(hide yes)
			(effects
				(font
					(size 1.27 1.27)
				)
			)
		)
		(property "Value" "SN74LVC1G08DCKR-GP"
			(at -2.3368 -8.6868 90)
			(unlocked yes)
			(layer "F.Fab")
			(hide yes)
			(effects
				(font
					(size 1.016 1.016)
					(thickness 0.1524)
				)
			)
		)
		(property "Device Type" "SC70-5H44"
			(at -2.3114 -10.414 90)
			(unlocked yes)
			(layer "F.Fab")
			(hide yes)
			(effects
				(font
					(size 1.016 1.016)
					(thickness 0.1524)
				)
			)
		)
		(duplicate_pad_numbers_are_jumpers no)
		(fp_line
			(start 1.3843 -1.8034)
			(end 1.3843 -1.1176)
			(stroke
				(width 0.3302)
				(type default)
			)
			(layer "F.SilkS")
		)
		(fp_line
			(start 0.6604 -1.8034)
			(end 1.3843 -1.8034)
			(stroke
				(width 0.3302)
				(type default)
			)
			(layer "F.SilkS")
		)
		(fp_line
			(start 1.27 -1.7018)
			(end 1.27 1.7018)
			(stroke
				(width 0.1524)
				(type default)
			)
			(layer "F.SilkS")
		)
		(fp_line
			(start -1.27 -1.7018)
			(end 1.27 -1.7018)
			(stroke
				(width 0.1524)
				(type default)
			)
			(layer "F.SilkS")
		)
		(fp_line
			(start 1.27 1.7018)
			(end -1.27 1.7018)
			(stroke
				(width 0.1524)
				(type default)
			)
			(layer "F.SilkS")
		)
		(fp_line
			(start -1.27 1.7018)
			(end -1.27 -1.7018)
			(stroke
				(width 0.1524)
				(type default)
			)
			(layer "F.SilkS")
		)
		(fp_rect
			(start -1.524 1.9558)
			(end 1.524 -1.9558)
			(stroke
				(width 0)
				(type default)
			)
			(fill no)
			(layer "F.CrtYd")
		)
		(fp_poly
			(pts
				(xy -1.524 -1.9558) (xy 1.524 -1.9558) (xy 1.524 1.9558) (xy -1.524 1.9558)
			)
			(stroke
				(width 0)
				(type default)
			)
			(fill no)
			(layer "F.Fab")
		)
		(pad "1" smd rect
			(at 0.65024 -0.8255 90)
			(size 0.4064 1.2192)
			(layers "F.Cu" "F.Mask" "F.Paste")
			(net "FM_BMC_RESET_Q36_R")
		)
		(pad "2" smd rect
			(at 0 -0.8255 90)
			(size 0.4064 1.2192)
			(layers "F.Cu" "F.Mask" "F.Paste")
			(net "U80_B")
		)
		(pad "3" smd rect
			(at -0.65024 -0.8255 90)
			(size 0.4064 1.2192)
			(layers "F.Cu" "F.Mask" "F.Paste")
			(net "GND")
		)
		(pad "4" smd rect
			(at -0.65024 0.8255 90)
			(size 0.4064 1.2192)
			(layers "F.Cu" "F.Mask" "F.Paste")
			(net "FM_BMC_RESET_N")
		)
		(pad "5" smd rect
			(at 0.65024 0.8255 90)
			(size 0.4064 1.2192)
			(layers "F.Cu" "F.Mask" "F.Paste")
			(net "P3V3_STBY")
		)
	)
)
